FILE_TYPE = MACRO_DRAWING;
SET COLOR_WIRE YELLOW;
SET COLOR_PROP MONO;
SET COLOR_DOT WHITE;
SET COLOR_ARC YELLOW;
SET COLOR_BODY GREEN;
SET COLOR_NOTE MONO;
SET PROP_DISPLAY VALUE;
SET PAGE_NUMBER P164;
FORCEADD RES..1
(-7025 1450);
FORCEPROP 1 LAST LOCATION R1T5
J 0
(-7225 1475);
DISPLAY 0.617021 (-7225 1475);
PAINT AQUA (-7225 1475);
FORCEPROP 1 LASTPIN (-7125 1450) $PN 1
J 0
(-7113 1462);
DISPLAY 0.617021 (-7113 1462);
PAINT ORANGE (-7113 1462);
FORCEPROP 1 LASTPIN (-6925 1450) $PN 2
J 0
(-6963 1462);
DISPLAY 0.617021 (-6963 1462);
PAINT ORANGE (-6963 1462);
FORCEPROP 1 LAST TOLERANCE 1%
J 0
(-6950 1400);
DISPLAY 0.617021 (-6950 1400);
PAINT SKYBLUE (-6950 1400);
FORCEPROP 1 LAST PART_NUMBER G21796-344
J 0
(-6925 1475);
DISPLAY 0.617021 (-6925 1475);
PAINT BLUE (-6925 1475);
FORCEPROP 1 LAST PACK_TYPE 0402
J 0
(-6575 1400);
DISPLAY 0.617021 (-6575 1400);
PAINT SKYBLUE (-6575 1400);
FORCEPROP 1 LAST MATERIAL EMPTY
J 0
(-6725 1400);
DISPLAY 0.617021 (-6725 1400);
PAINT RED (-6725 1400);
FORCEPROP 1 LAST WATTAGE 1/16W
J 2
(-6750 1400);
DISPLAY 0.617021 (-6750 1400);
PAINT SKYBLUE (-6750 1400);
FORCEPROP 1 LAST VALUE 2.7K
J 2
(-7050 1400);
DISPLAY 0.617021 (-7050 1400);
PAINT SKYBLUE (-7050 1400);
FORCEPROP 2 LAST CDS_LIB mstr_discrete
J 0
(-7025 1450);
PAINT ORANGE (-7025 1450);
DISPLAY INVISIBLE (-7025 1450);
FORCEPROP 2 LAST CDS_LOCATION R1T5
J 0
(-7025 1475);
DISPLAY 0.617021 (-7025 1475);
PAINT AQUA (-7025 1475);
DISPLAY INVISIBLE (-7025 1475);
FORCEPROP 2 LAST ROOM BMC_MISC
J 0
(-6925 1525);
DISPLAY 1.021277 (-6925 1525);
PAINT ORANGE (-6925 1525);
DISPLAY INVISIBLE (-6925 1525);
FORCEPROP 2 LAST SEC 1
J 0
(-7075 1650);
DISPLAY 0.680851 (-7075 1650);
PAINT MONO (-7075 1650);
DISPLAY INVISIBLE (-7075 1650);
FORCEPROP 1 LAST PATH I11
J 0
(-7075 1600);
DISPLAY 0.978723 (-7075 1600);
PAINT WHITE (-7075 1600);
DISPLAY INVISIBLE (-7075 1600);
FORCEPROP 2 LAST BOM_COST SM_CONTROLLER
J 0
(-6925 1575);
DISPLAY 1.021277 (-6925 1575);
PAINT ORANGE (-6925 1575);
DISPLAY INVISIBLE (-6925 1575);
FORCEPROP 2 LAST SEC_TYPE 0402
J 0
(-7075 1650);
DISPLAY 1.021277 (-7075 1650);
PAINT ORANGE (-7075 1650);
DISPLAY INVISIBLE (-7075 1650);
FORCEADD P3V3_STBY..1
(-7375 1600);
FORCEPROP 3 LASTPIN (-7375 1550) SIG_NAME P3V3_STBY\g
J 0
(-7365 1560);
DISPLAY 0.659574 (-7365 1560);
PAINT MONO (-7365 1560);
DISPLAY INVISIBLE (-7365 1560);
FORCEPROP 1 LAST HDL_POWER P3V3_STBY
J 0
(-7675 1475);
DISPLAY 0.872340 (-7675 1475);
PAINT ORANGE (-7675 1475);
DISPLAY INVISIBLE (-7675 1475);
FORCEPROP 1 LAST PATH I12
J 0
(-7330 1602);
DISPLAY 0.340426 (-7330 1602);
PAINT GREEN (-7330 1602);
DISPLAY INVISIBLE (-7330 1602);
FORCEPROP 1 LAST BODY_TYPE PLUMBING
J 0
(-7420 1557);
DISPLAY 0.340426 (-7420 1557);
PAINT GREEN (-7420 1557);
DISPLAY INVISIBLE (-7420 1557);
FORCEPROP 2 LAST CDS_LIB mstr_symbols
J 0
(-7375 1600);
PAINT ORANGE (-7375 1600);
DISPLAY INVISIBLE (-7375 1600);
FORCEPROP 1 LAST SIZE 1B
J 0
(-7330 1622);
DISPLAY 0.340426 (-7330 1622);
PAINT GREEN (-7330 1622);
DISPLAY INVISIBLE (-7330 1622);
FORCEPROP 1 LAST VOLTAGE 3.3V
J 0
(-7420 1557);
DISPLAY 0.340426 (-7420 1557);
PAINT SKYBLUE (-7420 1557);
DISPLAY INVISIBLE (-7420 1557);
FORCEADD RES..1
(-7025 1250);
FORCEPROP 1 LAST LOCATION R1T6
J 0
(-7225 1275);
DISPLAY 0.617021 (-7225 1275);
PAINT AQUA (-7225 1275);
FORCEPROP 1 LAST VALUE 2.7K
J 2
(-7050 1200);
DISPLAY 0.617021 (-7050 1200);
PAINT SKYBLUE (-7050 1200);
FORCEPROP 1 LASTPIN (-6925 1250) $PN 2
J 0
(-6963 1262);
DISPLAY 0.617021 (-6963 1262);
PAINT ORANGE (-6963 1262);
FORCEPROP 1 LASTPIN (-7125 1250) $PN 1
J 0
(-7113 1262);
DISPLAY 0.617021 (-7113 1262);
PAINT ORANGE (-7113 1262);
FORCEPROP 1 LAST TOLERANCE 1%
J 0
(-6950 1200);
DISPLAY 0.617021 (-6950 1200);
PAINT SKYBLUE (-6950 1200);
FORCEPROP 1 LAST WATTAGE 1/16W
J 2
(-6750 1200);
DISPLAY 0.617021 (-6750 1200);
PAINT SKYBLUE (-6750 1200);
FORCEPROP 1 LAST PART_NUMBER G21796-344
J 0
(-6925 1275);
DISPLAY 0.617021 (-6925 1275);
PAINT BLUE (-6925 1275);
FORCEPROP 1 LAST MATERIAL EMPTY
J 0
(-6725 1200);
DISPLAY 0.617021 (-6725 1200);
PAINT RED (-6725 1200);
FORCEPROP 1 LAST PACK_TYPE 0402
J 0
(-6575 1200);
DISPLAY 0.617021 (-6575 1200);
PAINT SKYBLUE (-6575 1200);
FORCEPROP 2 LAST CDS_LOCATION R1T6
J 0
(-7025 1275);
DISPLAY 0.617021 (-7025 1275);
PAINT AQUA (-7025 1275);
DISPLAY INVISIBLE (-7025 1275);
FORCEPROP 2 LAST CDS_LIB mstr_discrete
J 0
(-7025 1250);
PAINT ORANGE (-7025 1250);
DISPLAY INVISIBLE (-7025 1250);
FORCEPROP 1 LAST PATH I13
J 0
(-7075 1400);
DISPLAY 0.978723 (-7075 1400);
PAINT WHITE (-7075 1400);
DISPLAY INVISIBLE (-7075 1400);
FORCEPROP 2 LAST SEC_TYPE 0402
J 0
(-7075 1450);
DISPLAY 1.021277 (-7075 1450);
PAINT ORANGE (-7075 1450);
DISPLAY INVISIBLE (-7075 1450);
FORCEPROP 2 LAST SEC 1
J 0
(-7075 1450);
DISPLAY 0.680851 (-7075 1450);
PAINT MONO (-7075 1450);
DISPLAY INVISIBLE (-7075 1450);
FORCEPROP 2 LAST ROOM BMC_MISC
J 0
(-6925 1325);
DISPLAY 1.021277 (-6925 1325);
PAINT ORANGE (-6925 1325);
DISPLAY INVISIBLE (-6925 1325);
FORCEPROP 2 LAST BOM_COST SM_CONTROLLER
J 0
(-6925 1375);
DISPLAY 1.021277 (-6925 1375);
PAINT ORANGE (-6925 1375);
DISPLAY INVISIBLE (-6925 1375);
FORCEADD RES..1
(-7025 1050);
FORCEPROP 1 LAST LOCATION R1T4
J 0
(-7225 1075);
DISPLAY 0.617021 (-7225 1075);
PAINT AQUA (-7225 1075);
FORCEPROP 1 LAST WATTAGE 1/16W
J 2
(-6750 1000);
DISPLAY 0.617021 (-6750 1000);
PAINT SKYBLUE (-6750 1000);
FORCEPROP 1 LAST VALUE 2.7K
J 2
(-7050 1000);
DISPLAY 0.617021 (-7050 1000);
PAINT SKYBLUE (-7050 1000);
FORCEPROP 1 LAST TOLERANCE 1%
J 0
(-6950 1000);
DISPLAY 0.617021 (-6950 1000);
PAINT SKYBLUE (-6950 1000);
FORCEPROP 1 LAST PACK_TYPE 0402
J 0
(-6575 1000);
DISPLAY 0.617021 (-6575 1000);
PAINT SKYBLUE (-6575 1000);
FORCEPROP 1 LAST MATERIAL CHIP
J 0
(-6725 1000);
DISPLAY 0.617021 (-6725 1000);
PAINT SKYBLUE (-6725 1000);
FORCEPROP 1 LASTPIN (-7125 1050) $PN 1
J 0
(-7113 1062);
DISPLAY 0.617021 (-7113 1062);
PAINT ORANGE (-7113 1062);
FORCEPROP 1 LASTPIN (-6925 1050) $PN 2
J 0
(-6963 1062);
DISPLAY 0.617021 (-6963 1062);
PAINT ORANGE (-6963 1062);
FORCEPROP 1 LAST PART_NUMBER G21796-344
J 0
(-6925 1075);
DISPLAY 0.617021 (-6925 1075);
PAINT BLUE (-6925 1075);
FORCEPROP 2 LAST SEC 1
J 0
(-7075 1250);
DISPLAY 0.680851 (-7075 1250);
PAINT MONO (-7075 1250);
DISPLAY INVISIBLE (-7075 1250);
FORCEPROP 1 LAST PATH I14
J 0
(-7075 1200);
DISPLAY 0.978723 (-7075 1200);
PAINT WHITE (-7075 1200);
DISPLAY INVISIBLE (-7075 1200);
FORCEPROP 2 LAST CDS_LIB mstr_discrete
J 0
(-7025 1050);
PAINT ORANGE (-7025 1050);
DISPLAY INVISIBLE (-7025 1050);
FORCEPROP 2 LAST CDS_LOCATION R1T4
J 0
(-7025 1075);
DISPLAY 0.617021 (-7025 1075);
PAINT AQUA (-7025 1075);
DISPLAY INVISIBLE (-7025 1075);
FORCEPROP 2 LAST ROOM BMC_MISC
J 0
(-6925 1125);
DISPLAY 1.021277 (-6925 1125);
PAINT ORANGE (-6925 1125);
DISPLAY INVISIBLE (-6925 1125);
FORCEPROP 2 LAST BOM_COST SM_CONTROLLER
J 0
(-6925 1175);
DISPLAY 1.021277 (-6925 1175);
PAINT ORANGE (-6925 1175);
DISPLAY INVISIBLE (-6925 1175);
FORCEPROP 2 LAST SEC_TYPE 0402
J 0
(-7075 1250);
DISPLAY 1.021277 (-7075 1250);
PAINT ORANGE (-7075 1250);
DISPLAY INVISIBLE (-7075 1250);
FORCEADD OFFPAGE..2
(-5050 3075);
FORCEPROP 2 LAST $XR0 120 
J 0
(-4861 3075);
DISPLAY 0.638298 (-4861 3075);
PAINT MONO (-4861 3075);
FORCEPROP 2 LAST $XR1 147 
J 0
(-4741 3075);
DISPLAY 0.638298 (-4741 3075);
PAINT MONO (-4741 3075);
FORCEPROP 1 LAST COMMENT_BODY TRUE
J 0
(-5095 2980);
DISPLAY 0.872340 (-5095 2980);
PAINT GREEN (-5095 2980);
DISPLAY INVISIBLE (-5095 2980);
FORCEPROP 1 LAST OFFPAGE TRUE
J 0
(-4725 2950);
DISPLAY 0.872340 (-4725 2950);
PAINT GREEN (-4725 2950);
DISPLAY INVISIBLE (-4725 2950);
FORCEPROP 2 LAST CDS_LIB mstr_standard
J 0
(-5050 3075);
PAINT ORANGE (-5050 3075);
DISPLAY INVISIBLE (-5050 3075);
FORCEPROP 2 LAST PATH I15
J 0
(-4875 3150);
DISPLAY 1.021277 (-4875 3150);
PAINT ORANGE (-4875 3150);
DISPLAY INVISIBLE (-4875 3150);
FORCEADD OFFPAGE..2
(-5050 2875);
FORCEPROP 2 LAST $XR0 120 
J 0
(-4861 2875);
DISPLAY 0.638298 (-4861 2875);
PAINT MONO (-4861 2875);
FORCEPROP 2 LAST $XR1 147 
J 0
(-4741 2875);
DISPLAY 0.638298 (-4741 2875);
PAINT MONO (-4741 2875);
FORCEPROP 1 LAST COMMENT_BODY TRUE
J 0
(-5095 2780);
DISPLAY 0.872340 (-5095 2780);
PAINT GREEN (-5095 2780);
DISPLAY INVISIBLE (-5095 2780);
FORCEPROP 2 LAST CDS_LIB mstr_standard
J 0
(-5050 2875);
PAINT ORANGE (-5050 2875);
DISPLAY INVISIBLE (-5050 2875);
FORCEPROP 2 LAST PATH I16
J 0
(-4875 2950);
DISPLAY 1.021277 (-4875 2950);
PAINT ORANGE (-4875 2950);
DISPLAY INVISIBLE (-4875 2950);
FORCEPROP 1 LAST OFFPAGE TRUE
J 0
(-4725 2750);
DISPLAY 0.872340 (-4725 2750);
PAINT GREEN (-4725 2750);
DISPLAY INVISIBLE (-4725 2750);
FORCEADD OFFPAGE..2
(-5050 2675);
FORCEPROP 2 LAST $XR0 120 
J 0
(-4861 2675);
DISPLAY 0.638298 (-4861 2675);
PAINT MONO (-4861 2675);
FORCEPROP 2 LAST $XR1 147 
J 0
(-4741 2675);
DISPLAY 0.638298 (-4741 2675);
PAINT MONO (-4741 2675);
FORCEPROP 1 LAST OFFPAGE TRUE
J 0
(-4725 2550);
DISPLAY 0.872340 (-4725 2550);
PAINT GREEN (-4725 2550);
DISPLAY INVISIBLE (-4725 2550);
FORCEPROP 1 LAST COMMENT_BODY TRUE
J 0
(-5095 2580);
DISPLAY 0.872340 (-5095 2580);
PAINT GREEN (-5095 2580);
DISPLAY INVISIBLE (-5095 2580);
FORCEPROP 2 LAST CDS_LIB mstr_standard
J 0
(-5050 2675);
PAINT ORANGE (-5050 2675);
DISPLAY INVISIBLE (-5050 2675);
FORCEPROP 2 LAST PATH I17
J 0
(-4875 2750);
DISPLAY 1.021277 (-4875 2750);
PAINT ORANGE (-4875 2750);
DISPLAY INVISIBLE (-4875 2750);
FORCEADD OFFPAGE..2
(-5050 2475);
FORCEPROP 2 LAST $XR0 120 
J 0
(-4861 2475);
DISPLAY 0.638298 (-4861 2475);
PAINT MONO (-4861 2475);
FORCEPROP 2 LAST $XR1 147 
J 0
(-4741 2475);
DISPLAY 0.638298 (-4741 2475);
PAINT MONO (-4741 2475);
FORCEPROP 1 LAST COMMENT_BODY TRUE
J 0
(-5095 2380);
DISPLAY 0.872340 (-5095 2380);
PAINT GREEN (-5095 2380);
DISPLAY INVISIBLE (-5095 2380);
FORCEPROP 2 LAST CDS_LIB mstr_standard
J 0
(-5050 2475);
PAINT ORANGE (-5050 2475);
DISPLAY INVISIBLE (-5050 2475);
FORCEPROP 1 LAST OFFPAGE TRUE
J 0
(-4725 2350);
DISPLAY 0.872340 (-4725 2350);
PAINT GREEN (-4725 2350);
DISPLAY INVISIBLE (-4725 2350);
FORCEPROP 2 LAST PATH I18
J 0
(-4875 2550);
DISPLAY 1.021277 (-4875 2550);
PAINT ORANGE (-4875 2550);
DISPLAY INVISIBLE (-4875 2550);
FORCEADD RES..2
(-5475 2150);
FORCEPROP 1 LAST LOCATION R1U18
J 0
(-5430 2275);
DISPLAY 0.617021 (-5430 2275);
PAINT AQUA (-5430 2275);
FORCEPROP 1 LAST VALUE 1.00K
J 0
(-5430 2225);
DISPLAY 0.617021 (-5430 2225);
PAINT SKYBLUE (-5430 2225);
FORCEPROP 1 LAST WATTAGE 1/16W
J 0
(-5435 2125);
DISPLAY 0.617021 (-5435 2125);
PAINT SKYBLUE (-5435 2125);
FORCEPROP 1 LAST TOLERANCE 1%
J 0
(-5430 2175);
DISPLAY 0.617021 (-5430 2175);
PAINT SKYBLUE (-5430 2175);
FORCEPROP 1 LASTPIN (-5475 2250) $PN 1
J 0
(-5470 2212);
DISPLAY 0.617021 (-5470 2212);
PAINT ORANGE (-5470 2212);
FORCEPROP 1 LASTPIN (-5475 2050) $PN 2
J 0
(-5470 2060);
DISPLAY 0.617021 (-5470 2060);
PAINT ORANGE (-5470 2060);
FORCEPROP 1 LAST PART_NUMBER G21796-026
J 0
(-5435 2025);
DISPLAY 0.617021 (-5435 2025);
PAINT BLUE (-5435 2025);
FORCEPROP 1 LAST PACK_TYPE 0402
J 0
(-5435 1975);
DISPLAY 0.617021 (-5435 1975);
PAINT SKYBLUE (-5435 1975);
FORCEPROP 1 LAST MATERIAL CHIP
J 0
(-5435 2075);
DISPLAY 0.617021 (-5435 2075);
PAINT RED (-5435 2075);
FORCEPROP 2 LAST ROOM BMC_MISC
J 0
(-5425 2325);
DISPLAY 1.021277 (-5425 2325);
PAINT ORANGE (-5425 2325);
DISPLAY INVISIBLE (-5425 2325);
FORCEPROP 1 LAST PATH I19
J 0
(-5425 2325);
DISPLAY 0.978723 (-5425 2325);
PAINT WHITE (-5425 2325);
DISPLAY INVISIBLE (-5425 2325);
FORCEPROP 2 LAST SEC 1
J 0
(-5425 2375);
DISPLAY 0.680851 (-5425 2375);
PAINT MONO (-5425 2375);
DISPLAY INVISIBLE (-5425 2375);
FORCEPROP 2 LAST BOM_COST SM_CONTROLLER
J 0
(-5425 2375);
DISPLAY 1.021277 (-5425 2375);
PAINT ORANGE (-5425 2375);
DISPLAY INVISIBLE (-5425 2375);
FORCEPROP 2 LAST SEC_TYPE 0402
J 0
(-5425 2375);
DISPLAY 1.021277 (-5425 2375);
PAINT ORANGE (-5425 2375);
DISPLAY INVISIBLE (-5425 2375);
FORCEPROP 2 LAST CDS_LOCATION R1U18
J 0
(-5430 2275);
DISPLAY 0.617021 (-5430 2275);
PAINT AQUA (-5430 2275);
DISPLAY INVISIBLE (-5430 2275);
FORCEPROP 2 LAST CDS_LIB mstr_discrete
J 0
(-5475 2150);
PAINT ORANGE (-5475 2150);
DISPLAY INVISIBLE (-5475 2150);
FORCEADD OFFPAGE..2
(-5500 1450);
FORCEPROP 2 LAST $XR0 119 
J 0
(-5311 1450);
DISPLAY 0.638298 (-5311 1450);
PAINT MONO (-5311 1450);
FORCEPROP 2 LAST $XR1 145 
J 0
(-5191 1450);
DISPLAY 0.638298 (-5191 1450);
PAINT MONO (-5191 1450);
FORCEPROP 2 LAST CDS_LIB mstr_standard
J 0
(-5500 1450);
PAINT ORANGE (-5500 1450);
DISPLAY INVISIBLE (-5500 1450);
FORCEPROP 1 LAST COMMENT_BODY TRUE
J 0
(-5545 1355);
DISPLAY 0.872340 (-5545 1355);
PAINT GREEN (-5545 1355);
DISPLAY INVISIBLE (-5545 1355);
FORCEPROP 1 LAST OFFPAGE TRUE
J 0
(-5175 1325);
DISPLAY 0.872340 (-5175 1325);
PAINT GREEN (-5175 1325);
DISPLAY INVISIBLE (-5175 1325);
FORCEPROP 2 LAST PATH I2
J 0
(-5325 1525);
DISPLAY 1.021277 (-5325 1525);
PAINT ORANGE (-5325 1525);
DISPLAY INVISIBLE (-5325 1525);
FORCEADD RES..2
(-5725 2150);
FORCEPROP 1 LAST VALUE 1.00K
J 0
(-5680 2225);
DISPLAY 0.617021 (-5680 2225);
PAINT SKYBLUE (-5680 2225);
FORCEPROP 1 LAST LOCATION R1U16
J 0
(-5680 2275);
DISPLAY 0.617021 (-5680 2275);
PAINT AQUA (-5680 2275);
FORCEPROP 1 LAST TOLERANCE 1%
J 0
(-5680 2175);
DISPLAY 0.617021 (-5680 2175);
PAINT SKYBLUE (-5680 2175);
FORCEPROP 1 LASTPIN (-5725 2250) $PN 1
J 0
(-5720 2212);
DISPLAY 0.617021 (-5720 2212);
PAINT ORANGE (-5720 2212);
FORCEPROP 1 LASTPIN (-5725 2050) $PN 2
J 0
(-5720 2060);
DISPLAY 0.617021 (-5720 2060);
PAINT ORANGE (-5720 2060);
FORCEPROP 1 LAST PACK_TYPE 0402
J 0
(-5685 1975);
DISPLAY 0.617021 (-5685 1975);
PAINT SKYBLUE (-5685 1975);
FORCEPROP 1 LAST PART_NUMBER G21796-026
J 0
(-5685 2025);
DISPLAY 0.617021 (-5685 2025);
PAINT BLUE (-5685 2025);
FORCEPROP 1 LAST MATERIAL EMPTY
J 0
(-5685 2075);
DISPLAY 0.617021 (-5685 2075);
PAINT SKYBLUE (-5685 2075);
FORCEPROP 1 LAST WATTAGE 1/16W
J 0
(-5685 2125);
DISPLAY 0.617021 (-5685 2125);
PAINT SKYBLUE (-5685 2125);
FORCEPROP 2 LAST ROOM BMC_MISC
J 0
(-5675 2325);
DISPLAY 1.021277 (-5675 2325);
PAINT ORANGE (-5675 2325);
DISPLAY INVISIBLE (-5675 2325);
FORCEPROP 1 LAST PATH I20
J 0
(-5675 2325);
DISPLAY 0.978723 (-5675 2325);
PAINT WHITE (-5675 2325);
DISPLAY INVISIBLE (-5675 2325);
FORCEPROP 2 LAST SEC 1
J 0
(-5675 2375);
DISPLAY 0.680851 (-5675 2375);
PAINT MONO (-5675 2375);
DISPLAY INVISIBLE (-5675 2375);
FORCEPROP 2 LAST BOM_COST SM_CONTROLLER
J 0
(-5675 2375);
DISPLAY 1.021277 (-5675 2375);
PAINT ORANGE (-5675 2375);
DISPLAY INVISIBLE (-5675 2375);
FORCEPROP 2 LAST SEC_TYPE 0402
J 0
(-5675 2375);
DISPLAY 1.021277 (-5675 2375);
PAINT ORANGE (-5675 2375);
DISPLAY INVISIBLE (-5675 2375);
FORCEPROP 2 LAST CDS_LOCATION R1U16
J 0
(-5680 2275);
DISPLAY 0.617021 (-5680 2275);
PAINT AQUA (-5680 2275);
DISPLAY INVISIBLE (-5680 2275);
FORCEPROP 2 LAST CDS_LIB mstr_discrete
J 0
(-5725 2150);
PAINT ORANGE (-5725 2150);
DISPLAY INVISIBLE (-5725 2150);
FORCEADD RES..2
(-5975 2150);
FORCEPROP 1 LAST TOLERANCE 1%
J 0
(-5930 2175);
DISPLAY 0.617021 (-5930 2175);
PAINT SKYBLUE (-5930 2175);
FORCEPROP 1 LAST VALUE 1.00K
J 0
(-5930 2225);
DISPLAY 0.617021 (-5930 2225);
PAINT SKYBLUE (-5930 2225);
FORCEPROP 1 LAST WATTAGE 1/16W
J 0
(-5935 2125);
DISPLAY 0.617021 (-5935 2125);
PAINT SKYBLUE (-5935 2125);
FORCEPROP 1 LASTPIN (-5975 2250) $PN 1
J 0
(-5970 2212);
DISPLAY 0.617021 (-5970 2212);
PAINT ORANGE (-5970 2212);
FORCEPROP 1 LASTPIN (-5975 2050) $PN 2
J 0
(-5970 2060);
DISPLAY 0.617021 (-5970 2060);
PAINT ORANGE (-5970 2060);
FORCEPROP 1 LAST MATERIAL CHIP
J 0
(-5935 2075);
DISPLAY 0.617021 (-5935 2075);
PAINT RED (-5935 2075);
FORCEPROP 1 LAST PACK_TYPE 0402
J 0
(-5935 1975);
DISPLAY 0.617021 (-5935 1975);
PAINT SKYBLUE (-5935 1975);
FORCEPROP 1 LAST PART_NUMBER G21796-026
J 0
(-5935 2025);
DISPLAY 0.617021 (-5935 2025);
PAINT BLUE (-5935 2025);
FORCEPROP 1 LAST LOCATION R1U17
J 0
(-5930 2275);
DISPLAY 0.617021 (-5930 2275);
PAINT AQUA (-5930 2275);
FORCEPROP 2 LAST ROOM BMC_MISC
J 0
(-5925 2325);
DISPLAY 1.021277 (-5925 2325);
PAINT ORANGE (-5925 2325);
DISPLAY INVISIBLE (-5925 2325);
FORCEPROP 1 LAST PATH I21
J 0
(-5925 2325);
DISPLAY 0.978723 (-5925 2325);
PAINT WHITE (-5925 2325);
DISPLAY INVISIBLE (-5925 2325);
FORCEPROP 2 LAST SEC 1
J 0
(-5925 2375);
DISPLAY 0.680851 (-5925 2375);
PAINT MONO (-5925 2375);
DISPLAY INVISIBLE (-5925 2375);
FORCEPROP 2 LAST SEC_TYPE 0402
J 0
(-5925 2375);
DISPLAY 1.021277 (-5925 2375);
PAINT ORANGE (-5925 2375);
DISPLAY INVISIBLE (-5925 2375);
FORCEPROP 2 LAST BOM_COST SM_CONTROLLER
J 0
(-5925 2375);
DISPLAY 1.021277 (-5925 2375);
PAINT ORANGE (-5925 2375);
DISPLAY INVISIBLE (-5925 2375);
FORCEPROP 2 LAST CDS_LOCATION R1U17
J 0
(-5930 2275);
DISPLAY 0.617021 (-5930 2275);
PAINT AQUA (-5930 2275);
DISPLAY INVISIBLE (-5930 2275);
FORCEPROP 2 LAST CDS_LIB mstr_discrete
J 0
(-5975 2150);
PAINT ORANGE (-5975 2150);
DISPLAY INVISIBLE (-5975 2150);
FORCEADD RES..2
(-6225 2150);
FORCEPROP 1 LAST TOLERANCE 1%
J 0
(-6180 2175);
DISPLAY 0.617021 (-6180 2175);
PAINT SKYBLUE (-6180 2175);
FORCEPROP 1 LAST LOCATION R1U15
J 0
(-6180 2275);
DISPLAY 0.617021 (-6180 2275);
PAINT AQUA (-6180 2275);
FORCEPROP 1 LAST PACK_TYPE 0402
J 0
(-6185 1975);
DISPLAY 0.617021 (-6185 1975);
PAINT SKYBLUE (-6185 1975);
FORCEPROP 1 LAST WATTAGE 1/16W
J 0
(-6185 2125);
DISPLAY 0.617021 (-6185 2125);
PAINT SKYBLUE (-6185 2125);
FORCEPROP 1 LASTPIN (-6225 2250) $PN 1
J 0
(-6220 2212);
DISPLAY 0.617021 (-6220 2212);
PAINT ORANGE (-6220 2212);
FORCEPROP 1 LASTPIN (-6225 2050) $PN 2
J 0
(-6220 2060);
DISPLAY 0.617021 (-6220 2060);
PAINT ORANGE (-6220 2060);
FORCEPROP 1 LAST PART_NUMBER G21796-026
J 0
(-6185 2025);
DISPLAY 0.617021 (-6185 2025);
PAINT BLUE (-6185 2025);
FORCEPROP 1 LAST MATERIAL EMPTY
J 0
(-6185 2075);
DISPLAY 0.617021 (-6185 2075);
PAINT SKYBLUE (-6185 2075);
FORCEPROP 1 LAST VALUE 1.00K
J 0
(-6180 2225);
DISPLAY 0.617021 (-6180 2225);
PAINT SKYBLUE (-6180 2225);
FORCEPROP 2 LAST SEC_TYPE 0402
J 0
(-6175 2375);
DISPLAY 1.021277 (-6175 2375);
PAINT ORANGE (-6175 2375);
DISPLAY INVISIBLE (-6175 2375);
FORCEPROP 2 LAST BOM_COST SM_CONTROLLER
J 0
(-6175 2375);
DISPLAY 1.021277 (-6175 2375);
PAINT ORANGE (-6175 2375);
DISPLAY INVISIBLE (-6175 2375);
FORCEPROP 2 LAST ROOM BMC_MISC
J 0
(-6175 2325);
DISPLAY 1.021277 (-6175 2325);
PAINT ORANGE (-6175 2325);
DISPLAY INVISIBLE (-6175 2325);
FORCEPROP 1 LAST PATH I22
J 0
(-6175 2325);
DISPLAY 0.978723 (-6175 2325);
PAINT WHITE (-6175 2325);
DISPLAY INVISIBLE (-6175 2325);
FORCEPROP 2 LAST SEC 1
J 0
(-6175 2375);
DISPLAY 0.680851 (-6175 2375);
PAINT MONO (-6175 2375);
DISPLAY INVISIBLE (-6175 2375);
FORCEPROP 2 LAST CDS_LOCATION R1U15
J 0
(-6180 2275);
DISPLAY 0.617021 (-6180 2275);
PAINT AQUA (-6180 2275);
DISPLAY INVISIBLE (-6180 2275);
FORCEPROP 2 LAST CDS_LIB mstr_discrete
J 0
(-6225 2150);
PAINT ORANGE (-6225 2150);
DISPLAY INVISIBLE (-6225 2150);
FORCEADD RES..1
(-7025 3075);
FORCEPROP 1 LASTPIN (-6925 3075) $PN 2
J 0
(-6963 3087);
DISPLAY 0.617021 (-6963 3087);
PAINT ORANGE (-6963 3087);
FORCEPROP 1 LASTPIN (-7125 3075) $PN 1
J 0
(-7113 3087);
DISPLAY 0.617021 (-7113 3087);
PAINT ORANGE (-7113 3087);
FORCEPROP 1 LAST PACK_TYPE 0402
J 0
(-6575 3025);
DISPLAY 0.617021 (-6575 3025);
PAINT SKYBLUE (-6575 3025);
FORCEPROP 1 LAST PART_NUMBER G21796-344
J 0
(-6900 2975);
DISPLAY 0.617021 (-6900 2975);
PAINT BLUE (-6900 2975);
FORCEPROP 1 LAST WATTAGE 1/16W
J 2
(-6750 3025);
DISPLAY 0.617021 (-6750 3025);
PAINT SKYBLUE (-6750 3025);
FORCEPROP 1 LAST TOLERANCE 1%
J 0
(-6950 3025);
DISPLAY 0.617021 (-6950 3025);
PAINT SKYBLUE (-6950 3025);
FORCEPROP 1 LAST VALUE 2.7K
J 2
(-7050 3025);
DISPLAY 0.617021 (-7050 3025);
PAINT SKYBLUE (-7050 3025);
FORCEPROP 1 LAST LOCATION R1U21
J 0
(-7250 3100);
DISPLAY 0.617021 (-7250 3100);
PAINT AQUA (-7250 3100);
FORCEPROP 1 LAST MATERIAL CHIP
J 0
(-6725 3025);
DISPLAY 0.617021 (-6725 3025);
PAINT RED (-6725 3025);
FORCEPROP 2 LAST BOM_COST SM_CONTROLLER
J 0
(-6925 3200);
DISPLAY 1.021277 (-6925 3200);
PAINT ORANGE (-6925 3200);
DISPLAY INVISIBLE (-6925 3200);
FORCEPROP 2 LAST ROOM BMC_MISC
J 0
(-6925 3150);
DISPLAY 1.021277 (-6925 3150);
PAINT ORANGE (-6925 3150);
DISPLAY INVISIBLE (-6925 3150);
FORCEPROP 2 LAST CDS_LOCATION R1U21
J 0
(-7025 3100);
DISPLAY 0.617021 (-7025 3100);
PAINT AQUA (-7025 3100);
DISPLAY INVISIBLE (-7025 3100);
FORCEPROP 2 LAST CDS_LIB mstr_discrete
J 0
(-7025 3075);
PAINT ORANGE (-7025 3075);
DISPLAY INVISIBLE (-7025 3075);
FORCEPROP 1 LAST PATH I24
J 0
(-7075 3225);
DISPLAY 0.978723 (-7075 3225);
PAINT WHITE (-7075 3225);
DISPLAY INVISIBLE (-7075 3225);
FORCEPROP 2 LAST SEC 1
J 0
(-7075 3275);
DISPLAY 0.680851 (-7075 3275);
PAINT MONO (-7075 3275);
DISPLAY INVISIBLE (-7075 3275);
FORCEPROP 2 LAST SEC_TYPE 0402
J 0
(-7075 3275);
DISPLAY 1.021277 (-7075 3275);
PAINT ORANGE (-7075 3275);
DISPLAY INVISIBLE (-7075 3275);
FORCEADD RES..1
(-7025 2875);
FORCEPROP 1 LAST PACK_TYPE 0402
J 0
(-6575 2825);
DISPLAY 0.617021 (-6575 2825);
PAINT SKYBLUE (-6575 2825);
FORCEPROP 1 LAST PART_NUMBER G21796-344
J 0
(-6900 2775);
DISPLAY 0.617021 (-6900 2775);
PAINT BLUE (-6900 2775);
FORCEPROP 1 LAST WATTAGE 1/16W
J 2
(-6750 2825);
DISPLAY 0.617021 (-6750 2825);
PAINT SKYBLUE (-6750 2825);
FORCEPROP 1 LAST TOLERANCE 1%
J 0
(-6950 2825);
DISPLAY 0.617021 (-6950 2825);
PAINT SKYBLUE (-6950 2825);
FORCEPROP 1 LASTPIN (-6925 2875) $PN 2
J 0
(-6963 2887);
DISPLAY 0.617021 (-6963 2887);
PAINT ORANGE (-6963 2887);
FORCEPROP 1 LAST VALUE 2.7K
J 2
(-7050 2825);
DISPLAY 0.617021 (-7050 2825);
PAINT SKYBLUE (-7050 2825);
FORCEPROP 1 LASTPIN (-7125 2875) $PN 1
J 0
(-7113 2887);
DISPLAY 0.617021 (-7113 2887);
PAINT ORANGE (-7113 2887);
FORCEPROP 1 LAST LOCATION R1U24
J 0
(-7250 2900);
DISPLAY 0.617021 (-7250 2900);
PAINT AQUA (-7250 2900);
FORCEPROP 1 LAST MATERIAL EMPTY
J 0
(-6725 2825);
DISPLAY 0.617021 (-6725 2825);
PAINT SKYBLUE (-6725 2825);
FORCEPROP 2 LAST SEC_TYPE 0402
J 0
(-7075 3075);
DISPLAY 1.021277 (-7075 3075);
PAINT ORANGE (-7075 3075);
DISPLAY INVISIBLE (-7075 3075);
FORCEPROP 2 LAST SEC 1
J 0
(-7075 3075);
DISPLAY 0.680851 (-7075 3075);
PAINT MONO (-7075 3075);
DISPLAY INVISIBLE (-7075 3075);
FORCEPROP 2 LAST ROOM BMC_MISC
J 0
(-6925 2950);
DISPLAY 1.021277 (-6925 2950);
PAINT ORANGE (-6925 2950);
DISPLAY INVISIBLE (-6925 2950);
FORCEPROP 2 LAST BOM_COST SM_CONTROLLER
J 0
(-6925 3000);
DISPLAY 1.021277 (-6925 3000);
PAINT ORANGE (-6925 3000);
DISPLAY INVISIBLE (-6925 3000);
FORCEPROP 2 LAST CDS_LIB mstr_discrete
J 0
(-7025 2875);
PAINT ORANGE (-7025 2875);
DISPLAY INVISIBLE (-7025 2875);
FORCEPROP 2 LAST CDS_LOCATION R1U24
J 0
(-7025 2900);
DISPLAY 0.617021 (-7025 2900);
PAINT AQUA (-7025 2900);
DISPLAY INVISIBLE (-7025 2900);
FORCEPROP 1 LAST PATH I25
J 0
(-7075 3025);
DISPLAY 0.978723 (-7075 3025);
PAINT WHITE (-7075 3025);
DISPLAY INVISIBLE (-7075 3025);
FORCEADD P3V3_STBY..1
(-7375 3450);
FORCEPROP 3 LASTPIN (-7375 3400) SIG_NAME P3V3_STBY\g
J 0
(-7365 3410);
DISPLAY 0.659574 (-7365 3410);
PAINT MONO (-7365 3410);
DISPLAY INVISIBLE (-7365 3410);
FORCEPROP 1 LAST HDL_POWER P3V3_STBY
J 0
(-7675 3325);
DISPLAY 0.872340 (-7675 3325);
PAINT ORANGE (-7675 3325);
DISPLAY INVISIBLE (-7675 3325);
FORCEPROP 1 LAST BODY_TYPE PLUMBING
J 0
(-7420 3407);
DISPLAY 0.340426 (-7420 3407);
PAINT GREEN (-7420 3407);
DISPLAY INVISIBLE (-7420 3407);
FORCEPROP 1 LAST SIZE 1B
J 0
(-7330 3472);
DISPLAY 0.340426 (-7330 3472);
PAINT GREEN (-7330 3472);
DISPLAY INVISIBLE (-7330 3472);
FORCEPROP 2 LAST CDS_LIB mstr_symbols
J 0
(-7375 3450);
PAINT ORANGE (-7375 3450);
DISPLAY INVISIBLE (-7375 3450);
FORCEPROP 1 LAST VOLTAGE 3.3V
J 0
(-7420 3407);
DISPLAY 0.340426 (-7420 3407);
PAINT SKYBLUE (-7420 3407);
DISPLAY INVISIBLE (-7420 3407);
FORCEPROP 1 LAST PATH I26
J 0
(-7330 3452);
DISPLAY 0.340426 (-7330 3452);
PAINT GREEN (-7330 3452);
DISPLAY INVISIBLE (-7330 3452);
FORCEADD RES..1
(-7025 2675);
FORCEPROP 1 LAST PACK_TYPE 0402
J 0
(-6575 2625);
DISPLAY 0.617021 (-6575 2625);
PAINT SKYBLUE (-6575 2625);
FORCEPROP 1 LAST PART_NUMBER G21796-344
J 0
(-6900 2575);
DISPLAY 0.617021 (-6900 2575);
PAINT BLUE (-6900 2575);
FORCEPROP 1 LAST WATTAGE 1/16W
J 2
(-6750 2625);
DISPLAY 0.617021 (-6750 2625);
PAINT SKYBLUE (-6750 2625);
FORCEPROP 1 LAST TOLERANCE 1%
J 0
(-6950 2625);
DISPLAY 0.617021 (-6950 2625);
PAINT SKYBLUE (-6950 2625);
FORCEPROP 1 LASTPIN (-6925 2675) $PN 2
J 0
(-6963 2687);
DISPLAY 0.617021 (-6963 2687);
PAINT ORANGE (-6963 2687);
FORCEPROP 1 LASTPIN (-7125 2675) $PN 1
J 0
(-7113 2687);
DISPLAY 0.617021 (-7113 2687);
PAINT ORANGE (-7113 2687);
FORCEPROP 1 LAST VALUE 2.7K
J 2
(-7050 2625);
DISPLAY 0.617021 (-7050 2625);
PAINT SKYBLUE (-7050 2625);
FORCEPROP 1 LAST LOCATION R1U22
J 0
(-7250 2700);
DISPLAY 0.617021 (-7250 2700);
PAINT AQUA (-7250 2700);
FORCEPROP 1 LAST MATERIAL CHIP
J 0
(-6725 2625);
DISPLAY 0.617021 (-6725 2625);
PAINT RED (-6725 2625);
FORCEPROP 1 LAST PATH I27
J 0
(-7075 2825);
DISPLAY 0.978723 (-7075 2825);
PAINT WHITE (-7075 2825);
DISPLAY INVISIBLE (-7075 2825);
FORCEPROP 2 LAST SEC 1
J 0
(-7075 2875);
DISPLAY 0.680851 (-7075 2875);
PAINT MONO (-7075 2875);
DISPLAY INVISIBLE (-7075 2875);
FORCEPROP 2 LAST SEC_TYPE 0402
J 0
(-7075 2875);
DISPLAY 1.021277 (-7075 2875);
PAINT ORANGE (-7075 2875);
DISPLAY INVISIBLE (-7075 2875);
FORCEPROP 2 LAST BOM_COST SM_CONTROLLER
J 0
(-6925 2800);
DISPLAY 1.021277 (-6925 2800);
PAINT ORANGE (-6925 2800);
DISPLAY INVISIBLE (-6925 2800);
FORCEPROP 2 LAST ROOM BMC_MISC
J 0
(-6925 2750);
DISPLAY 1.021277 (-6925 2750);
PAINT ORANGE (-6925 2750);
DISPLAY INVISIBLE (-6925 2750);
FORCEPROP 2 LAST CDS_LOCATION R1U22
J 0
(-7025 2700);
DISPLAY 0.617021 (-7025 2700);
PAINT AQUA (-7025 2700);
DISPLAY INVISIBLE (-7025 2700);
FORCEPROP 2 LAST CDS_LIB mstr_discrete
J 0
(-7025 2675);
PAINT ORANGE (-7025 2675);
DISPLAY INVISIBLE (-7025 2675);
FORCEADD RES..1
(-7025 2475);
FORCEPROP 1 LAST PACK_TYPE 0402
J 0
(-6575 2425);
DISPLAY 0.617021 (-6575 2425);
PAINT SKYBLUE (-6575 2425);
FORCEPROP 1 LAST PART_NUMBER G21796-344
J 0
(-6900 2375);
DISPLAY 0.617021 (-6900 2375);
PAINT BLUE (-6900 2375);
FORCEPROP 1 LAST WATTAGE 1/16W
J 2
(-6750 2425);
DISPLAY 0.617021 (-6750 2425);
PAINT SKYBLUE (-6750 2425);
FORCEPROP 1 LAST TOLERANCE 1%
J 0
(-6950 2425);
DISPLAY 0.617021 (-6950 2425);
PAINT SKYBLUE (-6950 2425);
FORCEPROP 1 LASTPIN (-6925 2475) $PN 2
J 0
(-6963 2487);
DISPLAY 0.617021 (-6963 2487);
PAINT ORANGE (-6963 2487);
FORCEPROP 1 LASTPIN (-7125 2475) $PN 1
J 0
(-7113 2487);
DISPLAY 0.617021 (-7113 2487);
PAINT ORANGE (-7113 2487);
FORCEPROP 1 LAST VALUE 2.7K
J 2
(-7050 2425);
DISPLAY 0.617021 (-7050 2425);
PAINT SKYBLUE (-7050 2425);
FORCEPROP 1 LAST LOCATION R1U23
J 0
(-7250 2500);
DISPLAY 0.617021 (-7250 2500);
PAINT AQUA (-7250 2500);
FORCEPROP 1 LAST MATERIAL EMPTY
J 0
(-6725 2425);
DISPLAY 0.617021 (-6725 2425);
PAINT SKYBLUE (-6725 2425);
FORCEPROP 2 LAST BOM_COST SM_CONTROLLER
J 0
(-6925 2600);
DISPLAY 1.021277 (-6925 2600);
PAINT ORANGE (-6925 2600);
DISPLAY INVISIBLE (-6925 2600);
FORCEPROP 2 LAST SEC_TYPE 0402
J 0
(-7075 2675);
DISPLAY 1.021277 (-7075 2675);
PAINT ORANGE (-7075 2675);
DISPLAY INVISIBLE (-7075 2675);
FORCEPROP 2 LAST SEC 1
J 0
(-7075 2675);
DISPLAY 0.680851 (-7075 2675);
PAINT MONO (-7075 2675);
DISPLAY INVISIBLE (-7075 2675);
FORCEPROP 1 LAST PATH I28
J 0
(-7075 2625);
DISPLAY 0.978723 (-7075 2625);
PAINT WHITE (-7075 2625);
DISPLAY INVISIBLE (-7075 2625);
FORCEPROP 2 LAST ROOM BMC_MISC
J 0
(-6925 2550);
DISPLAY 1.021277 (-6925 2550);
PAINT ORANGE (-6925 2550);
DISPLAY INVISIBLE (-6925 2550);
FORCEPROP 2 LAST CDS_LOCATION R1U23
J 0
(-7025 2500);
DISPLAY 0.617021 (-7025 2500);
PAINT AQUA (-7025 2500);
DISPLAY INVISIBLE (-7025 2500);
FORCEPROP 2 LAST CDS_LIB mstr_discrete
J 0
(-7025 2475);
PAINT ORANGE (-7025 2475);
DISPLAY INVISIBLE (-7025 2475);
FORCEADD RES..1
(-7025 3275);
FORCEPROP 1 LAST TOLERANCE 1%
J 0
(-6950 3225);
DISPLAY 0.617021 (-6950 3225);
PAINT SKYBLUE (-6950 3225);
FORCEPROP 1 LAST WATTAGE 1/16W
J 2
(-6750 3225);
DISPLAY 0.617021 (-6750 3225);
PAINT SKYBLUE (-6750 3225);
FORCEPROP 1 LAST PART_NUMBER G21796-344
J 0
(-6900 3175);
DISPLAY 0.617021 (-6900 3175);
PAINT BLUE (-6900 3175);
FORCEPROP 1 LAST MATERIAL EMPTY
J 0
(-6725 3225);
DISPLAY 0.617021 (-6725 3225);
PAINT RED (-6725 3225);
FORCEPROP 1 LAST PACK_TYPE 0402
J 0
(-6575 3225);
DISPLAY 0.617021 (-6575 3225);
PAINT SKYBLUE (-6575 3225);
FORCEPROP 1 LAST LOCATION R2N17
J 0
(-7250 3300);
DISPLAY 0.617021 (-7250 3300);
PAINT AQUA (-7250 3300);
FORCEPROP 1 LAST VALUE 2.7K
J 2
(-7050 3225);
DISPLAY 0.617021 (-7050 3225);
PAINT SKYBLUE (-7050 3225);
FORCEPROP 1 LASTPIN (-7125 3275) $PN 1
J 0
(-7113 3287);
DISPLAY 0.787234 (-7113 3287);
PAINT ORANGE (-7113 3287);
DISPLAY INVISIBLE (-7113 3287);
FORCEPROP 2 LAST CDS_LOCATION R2N17
J 0
(-7025 3300);
DISPLAY 0.617021 (-7025 3300);
PAINT AQUA (-7025 3300);
DISPLAY INVISIBLE (-7025 3300);
FORCEPROP 2 LAST CDS_LIB mstr_discrete
J 0
(-7025 3275);
PAINT MONO (-7025 3275);
DISPLAY INVISIBLE (-7025 3275);
FORCEPROP 1 LASTPIN (-6925 3275) $PN 2
J 0
(-6963 3287);
DISPLAY 0.787234 (-6963 3287);
PAINT ORANGE (-6963 3287);
DISPLAY INVISIBLE (-6963 3287);
FORCEPROP 1 LAST PATH I29
J 0
(-7075 3425);
DISPLAY 0.978723 (-7075 3425);
PAINT WHITE (-7075 3425);
DISPLAY INVISIBLE (-7075 3425);
FORCEPROP 2 LAST $SEC 1
J 0
(-7075 3475);
PAINT MONO (-7075 3475);
DISPLAY INVISIBLE (-7075 3475);
FORCEPROP 2 LAST CDS_SEC 1
J 0
(-7075 3475);
PAINT MONO (-7075 3475);
DISPLAY INVISIBLE (-7075 3475);
FORCEPROP 2 LAST BOM_COST SM_CONTROLLER
J 0
(-6925 3400);
DISPLAY 1.021277 (-6925 3400);
PAINT ORANGE (-6925 3400);
DISPLAY INVISIBLE (-6925 3400);
FORCEPROP 2 LAST ROOM BMC_MISC
J 0
(-6925 3350);
DISPLAY 1.021277 (-6925 3350);
PAINT ORANGE (-6925 3350);
DISPLAY INVISIBLE (-6925 3350);
FORCEADD OFFPAGE..2
(-5500 1250);
FORCEPROP 2 LAST $XR0 119 
J 0
(-5311 1250);
DISPLAY 0.638298 (-5311 1250);
PAINT MONO (-5311 1250);
FORCEPROP 2 LAST $XR1 145 
J 0
(-5191 1250);
DISPLAY 0.638298 (-5191 1250);
PAINT MONO (-5191 1250);
FORCEPROP 1 LAST COMMENT_BODY TRUE
J 0
(-5545 1155);
DISPLAY 0.872340 (-5545 1155);
PAINT GREEN (-5545 1155);
DISPLAY INVISIBLE (-5545 1155);
FORCEPROP 2 LAST CDS_LIB mstr_standard
J 0
(-5500 1250);
PAINT ORANGE (-5500 1250);
DISPLAY INVISIBLE (-5500 1250);
FORCEPROP 1 LAST OFFPAGE TRUE
J 0
(-5175 1125);
DISPLAY 0.872340 (-5175 1125);
PAINT GREEN (-5175 1125);
DISPLAY INVISIBLE (-5175 1125);
FORCEPROP 2 LAST PATH I3
J 0
(-5325 1325);
DISPLAY 1.021277 (-5325 1325);
PAINT ORANGE (-5325 1325);
DISPLAY INVISIBLE (-5325 1325);
FORCEADD OFFPAGE..2
(-5050 3275);
FORCEPROP 2 LAST $XR0 120 
J 0
(-4861 3275);
DISPLAY 0.638298 (-4861 3275);
PAINT MONO (-4861 3275);
FORCEPROP 2 LAST $XR1 147 
J 0
(-4741 3275);
DISPLAY 0.638298 (-4741 3275);
PAINT MONO (-4741 3275);
FORCEPROP 1 LAST COMMENT_BODY TRUE
J 0
(-5095 3180);
DISPLAY 0.872340 (-5095 3180);
PAINT GREEN (-5095 3180);
DISPLAY INVISIBLE (-5095 3180);
FORCEPROP 2 LAST CDS_LIB mstr_standard
J 0
(-5050 3275);
PAINT MONO (-5050 3275);
DISPLAY INVISIBLE (-5050 3275);
FORCEPROP 2 LAST PATH I30
J 0
(-4870 3345);
DISPLAY 1.021277 (-4870 3345);
PAINT ORANGE (-4870 3345);
DISPLAY INVISIBLE (-4870 3345);
FORCEPROP 1 LAST OFFPAGE TRUE
J 0
(-4725 3150);
DISPLAY 0.872340 (-4725 3150);
PAINT GREEN (-4725 3150);
DISPLAY INVISIBLE (-4725 3150);
FORCEADD GND..1
(-6475 1850);
FORCEPROP 3 LASTPIN (-6475 1900) SIG_NAME GND\g
J 0
(-6465 1910);
DISPLAY 0.659574 (-6465 1910);
PAINT MONO (-6465 1910);
DISPLAY INVISIBLE (-6465 1910);
FORCEPROP 2 LAST CDS_LIB mstr_symbols
J 0
(-6475 1850);
PAINT MONO (-6475 1850);
DISPLAY INVISIBLE (-6475 1850);
FORCEPROP 1 LAST BODY_TYPE PLUMBING
J 0
(-6520 1807);
DISPLAY 0.340426 (-6520 1807);
PAINT GREEN (-6520 1807);
DISPLAY INVISIBLE (-6520 1807);
FORCEPROP 1 LAST VOLTAGE 0.0V
J 0
(-6520 1807);
DISPLAY 0.340426 (-6520 1807);
PAINT SKYBLUE (-6520 1807);
DISPLAY INVISIBLE (-6520 1807);
FORCEPROP 1 LAST HDL_POWER GND
J 0
(-6475 2000);
DISPLAY 0.872340 (-6475 2000);
PAINT GREEN (-6475 2000);
DISPLAY INVISIBLE (-6475 2000);
FORCEPROP 1 LAST SIZE 1B
J 0
(-6400 1800);
DISPLAY 0.872340 (-6400 1800);
PAINT AQUA (-6400 1800);
DISPLAY INVISIBLE (-6400 1800);
FORCEPROP 1 LAST PATH I31
J 0
(-6400 1850);
DISPLAY 0.872340 (-6400 1850);
PAINT AQUA (-6400 1850);
DISPLAY INVISIBLE (-6400 1850);
FORCEADD RES..2
(-6475 2150);
FORCEPROP 1 LAST PACK_TYPE 0402
J 0
(-6435 1975);
DISPLAY 0.617021 (-6435 1975);
PAINT SKYBLUE (-6435 1975);
FORCEPROP 1 LAST PART_NUMBER G21796-026
J 0
(-6435 2025);
DISPLAY 0.617021 (-6435 2025);
PAINT BLUE (-6435 2025);
FORCEPROP 1 LAST MATERIAL CHIP
J 0
(-6435 2075);
DISPLAY 0.617021 (-6435 2075);
PAINT SKYBLUE (-6435 2075);
FORCEPROP 1 LAST WATTAGE 1/16W
J 0
(-6435 2125);
DISPLAY 0.617021 (-6435 2125);
PAINT SKYBLUE (-6435 2125);
FORCEPROP 1 LAST VALUE 1.00K
J 0
(-6430 2225);
DISPLAY 0.617021 (-6430 2225);
PAINT SKYBLUE (-6430 2225);
FORCEPROP 1 LAST LOCATION R2N18
J 0
(-6430 2275);
DISPLAY 0.617021 (-6430 2275);
PAINT AQUA (-6430 2275);
FORCEPROP 1 LAST TOLERANCE 1%
J 0
(-6430 2175);
DISPLAY 0.617021 (-6430 2175);
PAINT SKYBLUE (-6430 2175);
FORCEPROP 1 LASTPIN (-6475 2050) $PN 2
J 0
(-6470 2060);
DISPLAY 0.787234 (-6470 2060);
PAINT ORANGE (-6470 2060);
DISPLAY INVISIBLE (-6470 2060);
FORCEPROP 2 LAST CDS_LIB mstr_discrete
J 0
(-6475 2150);
PAINT MONO (-6475 2150);
DISPLAY INVISIBLE (-6475 2150);
FORCEPROP 2 LAST CDS_LOCATION R2N18
J 0
(-6430 2275);
DISPLAY 0.617021 (-6430 2275);
PAINT AQUA (-6430 2275);
DISPLAY INVISIBLE (-6430 2275);
FORCEPROP 1 LASTPIN (-6475 2250) $PN 1
J 0
(-6470 2212);
DISPLAY 0.787234 (-6470 2212);
PAINT ORANGE (-6470 2212);
DISPLAY INVISIBLE (-6470 2212);
FORCEPROP 2 LAST $SEC 1
J 0
(-6425 2375);
PAINT MONO (-6425 2375);
DISPLAY INVISIBLE (-6425 2375);
FORCEPROP 2 LAST CDS_SEC 1
J 0
(-6425 2375);
PAINT MONO (-6425 2375);
DISPLAY INVISIBLE (-6425 2375);
FORCEPROP 2 LAST BOM_COST SM_CONTROLLER
J 0
(-6425 2375);
DISPLAY 1.021277 (-6425 2375);
PAINT ORANGE (-6425 2375);
DISPLAY INVISIBLE (-6425 2375);
FORCEPROP 1 LAST PATH I32
J 0
(-6425 2325);
DISPLAY 0.978723 (-6425 2325);
PAINT WHITE (-6425 2325);
DISPLAY INVISIBLE (-6425 2325);
FORCEPROP 2 LAST ROOM BMC_MISC
J 0
(-6425 2325);
DISPLAY 1.021277 (-6425 2325);
PAINT ORANGE (-6425 2325);
DISPLAY INVISIBLE (-6425 2325);
FORCEADD OFFPAGE..2
(-5500 1050);
FORCEPROP 2 LAST $XR0 119 
J 0
(-5311 1050);
DISPLAY 0.638298 (-5311 1050);
PAINT MONO (-5311 1050);
FORCEPROP 2 LAST $XR1 145 
J 0
(-5191 1050);
DISPLAY 0.638298 (-5191 1050);
PAINT MONO (-5191 1050);
FORCEPROP 1 LAST OFFPAGE TRUE
J 0
(-5175 925);
DISPLAY 0.872340 (-5175 925);
PAINT GREEN (-5175 925);
DISPLAY INVISIBLE (-5175 925);
FORCEPROP 1 LAST COMMENT_BODY TRUE
J 0
(-5545 955);
DISPLAY 0.872340 (-5545 955);
PAINT GREEN (-5545 955);
DISPLAY INVISIBLE (-5545 955);
FORCEPROP 2 LAST CDS_LIB mstr_standard
J 0
(-5500 1050);
PAINT ORANGE (-5500 1050);
DISPLAY INVISIBLE (-5500 1050);
FORCEPROP 2 LAST PATH I4
J 0
(-5325 1125);
DISPLAY 1.021277 (-5325 1125);
PAINT ORANGE (-5325 1125);
DISPLAY INVISIBLE (-5325 1125);
FORCEADD RES..2
(-5975 775);
FORCEPROP 1 LASTPIN (-5975 675) $PN 2
J 0
(-5970 685);
DISPLAY 0.617021 (-5970 685);
PAINT ORANGE (-5970 685);
FORCEPROP 1 LASTPIN (-5975 875) $PN 1
J 0
(-5970 837);
DISPLAY 0.617021 (-5970 837);
PAINT ORANGE (-5970 837);
FORCEPROP 1 LAST TOLERANCE 1%
J 0
(-5930 800);
DISPLAY 0.617021 (-5930 800);
PAINT SKYBLUE (-5930 800);
FORCEPROP 1 LAST MATERIAL EMPTY
J 0
(-5935 700);
DISPLAY 0.617021 (-5935 700);
PAINT RED (-5935 700);
FORCEPROP 1 LAST LOCATION R1T10
J 0
(-5930 900);
DISPLAY 0.617021 (-5930 900);
PAINT AQUA (-5930 900);
FORCEPROP 1 LAST PART_NUMBER G21796-026
J 0
(-5935 650);
DISPLAY 0.617021 (-5935 650);
PAINT BLUE (-5935 650);
FORCEPROP 1 LAST VALUE 1.00K
J 0
(-5930 850);
DISPLAY 0.617021 (-5930 850);
PAINT SKYBLUE (-5930 850);
FORCEPROP 1 LAST PACK_TYPE 0402
J 0
(-5935 600);
DISPLAY 0.617021 (-5935 600);
PAINT SKYBLUE (-5935 600);
FORCEPROP 1 LAST WATTAGE 1/16W
J 0
(-5935 750);
DISPLAY 0.617021 (-5935 750);
PAINT SKYBLUE (-5935 750);
FORCEPROP 2 LAST CDS_LIB mstr_discrete
J 0
(-5975 775);
PAINT ORANGE (-5975 775);
DISPLAY INVISIBLE (-5975 775);
FORCEPROP 2 LAST CDS_LOCATION R1T10
J 0
(-5930 900);
DISPLAY 0.617021 (-5930 900);
PAINT AQUA (-5930 900);
DISPLAY INVISIBLE (-5930 900);
FORCEPROP 1 LAST PATH I5
J 0
(-5925 950);
DISPLAY 0.978723 (-5925 950);
PAINT WHITE (-5925 950);
DISPLAY INVISIBLE (-5925 950);
FORCEPROP 2 LAST ROOM BMC_MISC
J 0
(-5925 950);
DISPLAY 1.021277 (-5925 950);
PAINT ORANGE (-5925 950);
DISPLAY INVISIBLE (-5925 950);
FORCEPROP 2 LAST SEC_TYPE 0402
J 0
(-5925 1000);
DISPLAY 1.021277 (-5925 1000);
PAINT ORANGE (-5925 1000);
DISPLAY INVISIBLE (-5925 1000);
FORCEPROP 2 LAST BOM_COST SM_CONTROLLER
J 0
(-5925 1000);
DISPLAY 1.021277 (-5925 1000);
PAINT ORANGE (-5925 1000);
DISPLAY INVISIBLE (-5925 1000);
FORCEPROP 2 LAST SEC 1
J 0
(-5925 1000);
DISPLAY 0.680851 (-5925 1000);
PAINT MONO (-5925 1000);
DISPLAY INVISIBLE (-5925 1000);
FORCEADD RES..2
(-6225 775);
FORCEPROP 1 LASTPIN (-6225 675) $PN 2
J 0
(-6220 685);
DISPLAY 0.617021 (-6220 685);
PAINT ORANGE (-6220 685);
FORCEPROP 1 LASTPIN (-6225 875) $PN 1
J 0
(-6220 837);
DISPLAY 0.617021 (-6220 837);
PAINT ORANGE (-6220 837);
FORCEPROP 1 LAST TOLERANCE 1%
J 0
(-6180 800);
DISPLAY 0.617021 (-6180 800);
PAINT SKYBLUE (-6180 800);
FORCEPROP 1 LAST PART_NUMBER G21796-026
J 0
(-6185 650);
DISPLAY 0.617021 (-6185 650);
PAINT BLUE (-6185 650);
FORCEPROP 1 LAST VALUE 1.00K
J 0
(-6180 850);
DISPLAY 0.617021 (-6180 850);
PAINT SKYBLUE (-6180 850);
FORCEPROP 1 LAST PACK_TYPE 0402
J 0
(-6185 600);
DISPLAY 0.617021 (-6185 600);
PAINT SKYBLUE (-6185 600);
FORCEPROP 1 LAST MATERIAL CHIP
J 0
(-6185 700);
DISPLAY 0.617021 (-6185 700);
PAINT SKYBLUE (-6185 700);
FORCEPROP 1 LAST WATTAGE 1/16W
J 0
(-6185 750);
DISPLAY 0.617021 (-6185 750);
PAINT SKYBLUE (-6185 750);
FORCEPROP 1 LAST LOCATION R1T12
J 0
(-6180 900);
DISPLAY 0.617021 (-6180 900);
PAINT AQUA (-6180 900);
FORCEPROP 2 LAST ROOM BMC_MISC
J 0
(-6175 950);
DISPLAY 1.021277 (-6175 950);
PAINT ORANGE (-6175 950);
DISPLAY INVISIBLE (-6175 950);
FORCEPROP 1 LAST PATH I6
J 0
(-6175 950);
DISPLAY 0.978723 (-6175 950);
PAINT WHITE (-6175 950);
DISPLAY INVISIBLE (-6175 950);
FORCEPROP 2 LAST CDS_LOCATION R1T12
J 0
(-6180 900);
DISPLAY 0.617021 (-6180 900);
PAINT AQUA (-6180 900);
DISPLAY INVISIBLE (-6180 900);
FORCEPROP 2 LAST CDS_LIB mstr_discrete
J 0
(-6225 775);
PAINT ORANGE (-6225 775);
DISPLAY INVISIBLE (-6225 775);
FORCEPROP 2 LAST BOM_COST SM_CONTROLLER
J 0
(-6175 1000);
DISPLAY 1.021277 (-6175 1000);
PAINT ORANGE (-6175 1000);
DISPLAY INVISIBLE (-6175 1000);
FORCEPROP 2 LAST SEC_TYPE 0402
J 0
(-6175 1000);
DISPLAY 1.021277 (-6175 1000);
PAINT ORANGE (-6175 1000);
DISPLAY INVISIBLE (-6175 1000);
FORCEPROP 2 LAST SEC 1
J 0
(-6175 1000);
DISPLAY 0.680851 (-6175 1000);
PAINT MONO (-6175 1000);
DISPLAY INVISIBLE (-6175 1000);
FORCEADD RES..2
(-6475 775);
FORCEPROP 1 LASTPIN (-6475 675) $PN 2
J 0
(-6470 685);
DISPLAY 0.617021 (-6470 685);
PAINT ORANGE (-6470 685);
FORCEPROP 1 LASTPIN (-6475 875) $PN 1
J 0
(-6470 837);
DISPLAY 0.617021 (-6470 837);
PAINT ORANGE (-6470 837);
FORCEPROP 1 LAST LOCATION R1T11
J 0
(-6430 900);
DISPLAY 0.617021 (-6430 900);
PAINT AQUA (-6430 900);
FORCEPROP 1 LAST PART_NUMBER G21796-026
J 0
(-6435 650);
DISPLAY 0.617021 (-6435 650);
PAINT BLUE (-6435 650);
FORCEPROP 1 LAST TOLERANCE 1%
J 0
(-6430 800);
DISPLAY 0.617021 (-6430 800);
PAINT SKYBLUE (-6430 800);
FORCEPROP 1 LAST PACK_TYPE 0402
J 0
(-6435 600);
DISPLAY 0.617021 (-6435 600);
PAINT SKYBLUE (-6435 600);
FORCEPROP 1 LAST MATERIAL CHIP
J 0
(-6435 700);
DISPLAY 0.617021 (-6435 700);
PAINT SKYBLUE (-6435 700);
FORCEPROP 1 LAST WATTAGE 1/16W
J 0
(-6435 750);
DISPLAY 0.617021 (-6435 750);
PAINT SKYBLUE (-6435 750);
FORCEPROP 1 LAST VALUE 1.00K
J 0
(-6430 850);
DISPLAY 0.617021 (-6430 850);
PAINT SKYBLUE (-6430 850);
FORCEPROP 2 LAST CDS_LIB mstr_discrete
J 0
(-6475 775);
PAINT ORANGE (-6475 775);
DISPLAY INVISIBLE (-6475 775);
FORCEPROP 2 LAST CDS_LOCATION R1T11
J 0
(-6430 900);
DISPLAY 0.617021 (-6430 900);
PAINT AQUA (-6430 900);
DISPLAY INVISIBLE (-6430 900);
FORCEPROP 1 LAST PATH I7
J 0
(-6425 950);
DISPLAY 0.978723 (-6425 950);
PAINT WHITE (-6425 950);
DISPLAY INVISIBLE (-6425 950);
FORCEPROP 2 LAST ROOM BMC_MISC
J 0
(-6425 950);
DISPLAY 1.021277 (-6425 950);
PAINT ORANGE (-6425 950);
DISPLAY INVISIBLE (-6425 950);
FORCEPROP 2 LAST SEC_TYPE 0402
J 0
(-6425 1000);
DISPLAY 1.021277 (-6425 1000);
PAINT ORANGE (-6425 1000);
DISPLAY INVISIBLE (-6425 1000);
FORCEPROP 2 LAST BOM_COST SM_CONTROLLER
J 0
(-6425 1000);
DISPLAY 1.021277 (-6425 1000);
PAINT ORANGE (-6425 1000);
DISPLAY INVISIBLE (-6425 1000);
FORCEPROP 2 LAST SEC 1
J 0
(-6425 1000);
DISPLAY 0.680851 (-6425 1000);
PAINT MONO (-6425 1000);
DISPLAY INVISIBLE (-6425 1000);
FORCEADD GND..1
(-6475 475);
FORCEPROP 3 LASTPIN (-6475 525) SIG_NAME GND\g
J 0
(-6465 535);
DISPLAY 0.659574 (-6465 535);
PAINT MONO (-6465 535);
DISPLAY INVISIBLE (-6465 535);
FORCEPROP 1 LAST VOLTAGE 0.0V
J 0
(-6520 432);
DISPLAY 0.340426 (-6520 432);
PAINT SKYBLUE (-6520 432);
DISPLAY INVISIBLE (-6520 432);
FORCEPROP 1 LAST SIZE 1B
J 0
(-6400 425);
DISPLAY 0.872340 (-6400 425);
PAINT AQUA (-6400 425);
DISPLAY INVISIBLE (-6400 425);
FORCEPROP 1 LAST BODY_TYPE PLUMBING
J 0
(-6520 432);
DISPLAY 0.340426 (-6520 432);
PAINT GREEN (-6520 432);
DISPLAY INVISIBLE (-6520 432);
FORCEPROP 1 LAST PATH I9
J 0
(-6400 475);
DISPLAY 0.872340 (-6400 475);
PAINT AQUA (-6400 475);
DISPLAY INVISIBLE (-6400 475);
FORCEPROP 2 LAST CDS_LIB mstr_symbols
J 0
(-6475 475);
PAINT ORANGE (-6475 475);
DISPLAY INVISIBLE (-6475 475);
FORCEPROP 1 LAST HDL_POWER GND
J 0
(-6475 625);
DISPLAY 0.872340 (-6475 625);
PAINT GREEN (-6475 625);
DISPLAY INVISIBLE (-6475 625);
FORCEADD DNS..2
(-7020 1245);
PAINT RED (-7020 1245);
FORCEPROP 1 LAST COMMENT_BODY TRUE
R 1
J 0
(-6945 1020);
DISPLAY 0.872340 (-6945 1020);
PAINT GREEN (-6945 1020);
DISPLAY INVISIBLE (-6945 1020);
FORCEPROP 2 LAST CDS_LIB mstr_misc
J 0
(-7020 1245);
PAINT ORANGE (-7020 1245);
DISPLAY INVISIBLE (-7020 1245);
FORCEADD DNS..2
(-5970 770);
PAINT RED (-5970 770);
FORCEPROP 1 LAST COMMENT_BODY TRUE
R 1
J 0
(-5895 545);
DISPLAY 0.872340 (-5895 545);
PAINT GREEN (-5895 545);
DISPLAY INVISIBLE (-5895 545);
FORCEPROP 2 LAST CDS_LIB mstr_misc
J 0
(-5970 770);
PAINT ORANGE (-5970 770);
DISPLAY INVISIBLE (-5970 770);
FORCEADD DNS..2
(-7020 1445);
PAINT RED (-7020 1445);
FORCEPROP 1 LAST COMMENT_BODY TRUE
R 1
J 0
(-6945 1220);
DISPLAY 0.872340 (-6945 1220);
PAINT GREEN (-6945 1220);
DISPLAY INVISIBLE (-6945 1220);
FORCEPROP 2 LAST CDS_LIB mstr_misc
J 0
(-7020 1445);
PAINT ORANGE (-7020 1445);
DISPLAY INVISIBLE (-7020 1445);
FORCEADD DNS..2
(-7020 3270);
PAINT RED (-7020 3270);
FORCEPROP 1 LAST COMMENT_BODY TRUE
R 1
J 0
(-6945 3045);
DISPLAY 0.872340 (-6945 3045);
PAINT GREEN (-6945 3045);
DISPLAY INVISIBLE (-6945 3045);
FORCEPROP 2 LAST CDS_LIB mstr_misc
J 0
(-7020 3270);
PAINT ORANGE (-7020 3270);
DISPLAY INVISIBLE (-7020 3270);
FORCEADD DNS..2
(-7020 2870);
PAINT RED (-7020 2870);
FORCEPROP 2 LAST CDS_LIB mstr_misc
J 0
(-7020 2870);
PAINT ORANGE (-7020 2870);
DISPLAY INVISIBLE (-7020 2870);
FORCEPROP 1 LAST COMMENT_BODY TRUE
R 1
J 0
(-6945 2645);
DISPLAY 0.872340 (-6945 2645);
PAINT GREEN (-6945 2645);
DISPLAY INVISIBLE (-6945 2645);
FORCEADD DNS..2
(-6220 2170);
PAINT RED (-6220 2170);
FORCEPROP 2 LAST CDS_LIB mstr_misc
J 0
(-6220 2170);
PAINT ORANGE (-6220 2170);
DISPLAY INVISIBLE (-6220 2170);
FORCEPROP 1 LAST COMMENT_BODY TRUE
R 1
J 0
(-6145 1945);
DISPLAY 0.872340 (-6145 1945);
PAINT GREEN (-6145 1945);
DISPLAY INVISIBLE (-6145 1945);
FORCEADD DNS..2
(-5720 2145);
PAINT RED (-5720 2145);
FORCEPROP 2 LAST CDS_LIB mstr_misc
J 0
(-5720 2145);
PAINT ORANGE (-5720 2145);
DISPLAY INVISIBLE (-5720 2145);
FORCEPROP 1 LAST COMMENT_BODY TRUE
R 1
J 0
(-5645 1920);
DISPLAY 0.872340 (-5645 1920);
PAINT GREEN (-5645 1920);
DISPLAY INVISIBLE (-5645 1920);
FORCEADD DNS..2
(-7020 2470);
PAINT RED (-7020 2470);
FORCEPROP 2 LAST CDS_LIB mstr_misc
J 0
(-7020 2470);
PAINT ORANGE (-7020 2470);
DISPLAY INVISIBLE (-7020 2470);
FORCEPROP 1 LAST COMMENT_BODY TRUE
R 1
J 0
(-6945 2245);
DISPLAY 0.872340 (-6945 2245);
PAINT GREEN (-6945 2245);
DISPLAY INVISIBLE (-6945 2245);
FORCEADD INTEL_CORP_BPAGE..1
(0 0);
FORCEPROP 1 LAST CDS_CON_LAST_MODIFIED Tue Dec 01 11:52:11 2015
J 0
(-1425 325);
DISPLAY 1.361702 (-1425 325);
PAINT GREEN (-1425 325);
DISPLAY INVISIBLE (-1425 325);
FORCEPROP 1 LAST CUSTOM_TXT_CDS <CURRENT_DESIGN_SHEET> OF <TOTAL_DESIGN_SHEETS>
J 0
(-500 25);
PAINT GREEN (-500 25);
FORCEPROP 1 LAST CUSTOM_TXT_CDS <CON_LAST_MODIFIED>
J 0
(-1925 350);
PAINT GREEN (-1925 350);
FORCEPROP 2 LAST CUSTOM_TXT_CDS <XR_PAGE_TITLE>
J 0
(-7890 5250);
DISPLAY 0.638298 (-7890 5250);
PAINT PINK (-7890 5250);
DISPLAY INVISIBLE (-7890 5250);
FORCEPROP 1 LAST SCH_ADDRESS1 2200 Mission College Blvd.
J 0
(-3975 125);
DISPLAY 0.617021 (-3975 125);
PAINT GREEN (-3975 125);
FORCEPROP 1 LAST SCH_ADDRESS2 P.O. BOX 58119
J 0
(-3975 75);
DISPLAY 0.617021 (-3975 75);
PAINT GREEN (-3975 75);
FORCEPROP 1 LAST SCH_ADDRESS3 Santa Clara, CA 95052-8119
J 0
(-3975 25);
DISPLAY 0.617021 (-3975 25);
PAINT GREEN (-3975 25);
FORCEPROP 1 LAST SCH_TITLE BOARD AND SKU ID STRAPS
J 0
(-7950 50);
DISPLAY 1.212766 (-7950 50);
PAINT ORANGE (-7950 50);
FORCEPROP 1 LAST SCH_NUMBER H4694802
J 0
(-1300 150);
DISPLAY 1.212766 (-1300 150);
PAINT YELLOW (-1300 150);
FORCEPROP 1 LAST SCH_DEPT BESD
J 1
(-4450 100);
DISPLAY 1.212766 (-4450 100);
PAINT YELLOW (-4450 100);
FORCEPROP 1 LAST SCH_REV 2.420
J 0
(-250 150);
DISPLAY 0.978723 (-250 150);
PAINT YELLOW (-250 150);
FORCEPROP 2 LAST PAGE_BORDER TRUE
J 0
(-7890 5250);
DISPLAY 0.851064 (-7890 5250);
PAINT PINK (-7890 5250);
DISPLAY INVISIBLE (-7890 5250);
FORCEPROP 2 LAST CDS_LIB mstr_symbols
J 0
(0 0);
DISPLAY 1.361702 (0 0);
PAINT ORANGE (0 0);
DISPLAY INVISIBLE (0 0);
FORCEPROP 1 LAST COMMENT_BODY TRUE
J 0
(12 12);
DISPLAY 0.617021 (12 12);
PAINT GREEN (12 12);
DISPLAY INVISIBLE (12 12);
FORCEPROP 2 LAST CDS_XR_PAGE_TITLE CR-164 : @BASEBOARD_FAB2_LIB.BASEBOARD_FAB2(SCH_1):PAGE164
J 0
(-7890 5250);
DISPLAY 0.638298 (-7890 5250);
PAINT PINK (-7890 5250);
DISPLAY INVISIBLE (-7890 5250);
WIRE 16 -1 (-7375 1050)(-7125 1050);
WIRE 16 -1 (-7375 1050)(-7375 1250);
WIRE 16 -1 (-7375 1250)(-7125 1250);
WIRE 16 -1 (-7375 1250)(-7375 1450);
WIRE 16 -1 (-7375 1450)(-7125 1450);
WIRE 16 -1 (-7375 1450)(-7375 1550);
WIRE 16 -1 (-7375 2475)(-7125 2475);
WIRE 16 -1 (-7375 2475)(-7375 2675);
WIRE 16 -1 (-7375 2675)(-7125 2675);
WIRE 16 -1 (-7375 2675)(-7375 2875);
WIRE 16 -1 (-7375 2875)(-7125 2875);
WIRE 16 -1 (-7375 2875)(-7375 3075);
WIRE 16 -1 (-7375 3075)(-7125 3075);
WIRE 16 -1 (-7375 3275)(-7375 3075);
WIRE 16 -1 (-7375 3275)(-7125 3275);
WIRE 16 -1 (-7375 3400)(-7375 3275);
WIRE 16 -1 (-5475 2050)(-5475 1925);
WIRE 16 -1 (-5475 1925)(-5725 1925);
WIRE 16 -1 (-5725 2050)(-5725 1925);
WIRE 16 -1 (-5725 1925)(-5975 1925);
WIRE 16 -1 (-5975 2050)(-5975 1925);
WIRE 16 -1 (-5975 1925)(-6225 1925);
WIRE 16 -1 (-6225 1925)(-6225 2050);
WIRE 16 -1 (-6225 1925)(-6475 1925);
WIRE 16 -1 (-6475 1925)(-6475 2050);
WIRE 16 -1 (-6475 1900)(-6475 1925);
WIRE 16 -1 (-5975 675)(-5975 600);
WIRE 16 -1 (-5975 600)(-6225 600);
WIRE 16 -1 (-6225 675)(-6225 600);
WIRE 16 -1 (-6225 600)(-6475 600);
WIRE 16 -1 (-6475 675)(-6475 600);
WIRE 16 -1 (-6475 525)(-6475 600);
WIRE 16 -1 (-6925 2675)(-5725 2675);
FORCEPROP 2 LAST SIG_NAME FM_BOARD_SKU_ID1
J 0
(-5450 2685);
DISPLAY 0.617021 (-5450 2685);
PAINT ORANGE (-5450 2685);
WIRE 16 -1 (-5725 2675)(-5100 2675);
WIRE 16 -1 (-5725 2250)(-5725 2675);
WIRE 16 -1 (-6225 2250)(-6225 3075);
WIRE 16 -1 (-6225 3075)(-5100 3075);
FORCEPROP 2 LAST SIG_NAME FM_BOARD_SKU_ID3
J 0
(-5450 3085);
DISPLAY 0.617021 (-5450 3085);
PAINT ORANGE (-5450 3085);
WIRE 16 -1 (-6925 3075)(-6225 3075);
WIRE 16 -1 (-6925 2475)(-5475 2475);
FORCEPROP 2 LAST SIG_NAME FM_BOARD_SKU_ID0
J 0
(-5450 2485);
DISPLAY 0.617021 (-5450 2485);
PAINT ORANGE (-5450 2485);
WIRE 16 -1 (-5475 2475)(-5100 2475);
WIRE 16 -1 (-5475 2250)(-5475 2475);
WIRE 16 -1 (-6925 2875)(-5975 2875);
WIRE 16 -1 (-5975 2875)(-5100 2875);
FORCEPROP 2 LAST SIG_NAME FM_BOARD_SKU_ID2
J 0
(-5450 2885);
DISPLAY 0.617021 (-5450 2885);
PAINT ORANGE (-5450 2885);
WIRE 16 -1 (-5975 2250)(-5975 2875);
WIRE 16 -1 (-6475 2250)(-6475 3275);
WIRE 16 -1 (-5100 3275)(-6475 3275);
FORCEPROP 0 LAST SIG_NAME FM_BOARD_SKU_ID4
J 0
(-5450 3285);
DISPLAY 0.617021 (-5450 3285);
PAINT ORANGE (-5450 3285);
WIRE 16 -1 (-6475 3275)(-6925 3275);
WIRE 16 -1 (-4325 2775)(-2675 2775);
WIRE 16 -1 (-4325 2900)(-4325 2775);
WIRE 16 -1 (-4325 2775)(-4325 2625);
WIRE 16 -1 (-2675 2775)(-2675 2900);
WIRE 16 -1 (-2675 2625)(-2675 2775);
WIRE 16 -1 (-4325 2625)(-2675 2625);
WIRE 16 -1 (-2675 2500)(-2675 2625);
WIRE 16 -1 (-4325 2900)(-2675 2900);
WIRE 16 -1 (-2675 2900)(-2675 3000);
WIRE 16 -1 (-4325 2625)(-4325 2500);
WIRE 16 -1 (-4325 3000)(-4325 2900);
WIRE 16 -1 (-3550 3000)(-4325 3000);
WIRE 16 -1 (-4325 2500)(-3550 2500);
WIRE 16 -1 (-2675 3000)(-3550 3000);
WIRE 16 -1 (-3550 2500)(-2675 2500);
WIRE 16 -1 (-3550 3000)(-3550 2500);
WIRE 16 -1 (-6925 1450)(-6475 1450);
WIRE 16 -1 (-6475 1450)(-5550 1450);
FORCEPROP 2 LAST SIG_NAME FM_BOARD_REV_ID2
J 2
(-5550 1460);
DISPLAY 0.617021 (-5550 1460);
PAINT ORANGE (-5550 1460);
WIRE 16 -1 (-6475 875)(-6475 1450);
WIRE 16 -1 (-5975 875)(-5975 1050);
WIRE 16 -1 (-5975 1050)(-5550 1050);
WIRE 16 -1 (-6925 1050)(-5975 1050);
FORCEPROP 2 LAST SIG_NAME FM_BOARD_REV_ID0
J 2
(-5550 1060);
DISPLAY 0.617021 (-5550 1060);
PAINT ORANGE (-5550 1060);
WIRE 16 -1 (-4400 1325)(-3050 1325);
WIRE 16 -1 (-4400 1450)(-4400 1325);
WIRE 16 -1 (-4400 1325)(-4400 1175);
WIRE 16 -1 (-3050 1325)(-3050 1450);
WIRE 16 -1 (-3050 1175)(-3050 1325);
WIRE 16 -1 (-4400 1175)(-3050 1175);
WIRE 16 -1 (-3050 1050)(-3050 1175);
WIRE 16 -1 (-4400 1450)(-3050 1450);
WIRE 16 -1 (-3050 1450)(-3050 1550);
WIRE 16 -1 (-4400 1175)(-4400 1050);
WIRE 16 -1 (-4400 1550)(-4400 1450);
WIRE 16 -1 (-3500 1550)(-4400 1550);
WIRE 16 -1 (-4400 1050)(-3050 1050);
WIRE 16 -1 (-4400 1050)(-4400 925);
WIRE 16 -1 (-3050 1550)(-3500 1550);
WIRE 16 -1 (-3050 1050)(-3050 925);
WIRE 16 -1 (-3500 925)(-3050 925);
WIRE 16 -1 (-3500 1550)(-3500 925);
WIRE 16 -1 (-4400 925)(-3500 925);
WIRE 16 -1 (-6925 1250)(-6225 1250);
FORCEPROP 2 LAST SIG_NAME FM_BOARD_REV_ID1
J 2
(-5550 1260);
DISPLAY 0.617021 (-5550 1260);
PAINT ORANGE (-5550 1260);
WIRE 16 -1 (-6225 1250)(-5550 1250);
WIRE 16 -1 (-6225 875)(-6225 1250);
DOT 1 (-5725 2675);
DOT 1 (-6225 3075);
DOT 1 (-7375 1450);
DOT 1 (-7375 1250);
DOT 1 (-6475 600);
DOT 1 (-6225 600);
DOT 1 (-6475 1450);
DOT 1 (-6225 1250);
DOT 1 (-6475 1925);
DOT 1 (-6225 1925);
DOT 1 (-7375 2675);
DOT 1 (-7375 2875);
DOT 1 (-7375 3075);
DOT 1 (-7375 3275);
DOT 1 (-6475 3275);
DOT 1 (-5975 1050);
DOT 1 (-5975 1925);
DOT 1 (-5725 1925);
DOT 1 (-4400 1050);
DOT 1 (-4400 1175);
DOT 1 (-4400 1325);
DOT 1 (-4400 1450);
DOT 1 (-5975 2875);
DOT 1 (-5475 2475);
DOT 1 (-4325 2625);
DOT 1 (-4325 2775);
DOT 1 (-4325 2900);
DOT 1 (-3500 925);
DOT 1 (-3500 1550);
DOT 1 (-3050 1050);
DOT 1 (-3050 1175);
DOT 1 (-3050 1325);
DOT 1 (-3050 1450);
DOT 1 (-3550 2500);
DOT 1 (-3550 3000);
DOT 1 (-2675 2775);
DOT 1 (-2675 2625);
DOT 1 (-2675 2900);
FORCENOTE
1
(-4125 2675) 0;
DISPLAY LEFT (-4125 2675);
DISPLAY 1.021277 (-4125 2675);
PAINT PURPLE (-4125 2675);
FORCENOTE
0
(-4000 2675) 0;
DISPLAY LEFT (-4000 2675);
DISPLAY 1.021277 (-4000 2675);
PAINT PURPLE (-4000 2675);
FORCENOTE
1
(-3875 2675) 0;
DISPLAY LEFT (-3875 2675);
DISPLAY 1.021277 (-3875 2675);
PAINT PURPLE (-3875 2675);
FORCENOTE
0
(-3725 2675) 0;
DISPLAY LEFT (-3725 2675);
DISPLAY 1.021277 (-3725 2675);
PAINT PURPLE (-3725 2675);
FORCENOTE
0
(-4250 2675) 0;
DISPLAY LEFT (-4250 2675);
DISPLAY 1.021277 (-4250 2675);
PAINT PURPLE (-4250 2675);
FORCENOTE
1
(-3725 2800) 0;
DISPLAY LEFT (-3725 2800);
DISPLAY 1.021277 (-3725 2800);
PAINT PURPLE (-3725 2800);
FORCENOTE
0
(-3875 2800) 0;
DISPLAY LEFT (-3875 2800);
DISPLAY 1.021277 (-3875 2800);
PAINT PURPLE (-3875 2800);
FORCENOTE
0
(-4000 2800) 0;
DISPLAY LEFT (-4000 2800);
DISPLAY 1.021277 (-4000 2800);
PAINT PURPLE (-4000 2800);
FORCENOTE
1
(-4125 2800) 0;
DISPLAY LEFT (-4125 2800);
DISPLAY 1.021277 (-4125 2800);
PAINT PURPLE (-4125 2800);
FORCENOTE
0
(-4250 2800) 0;
DISPLAY LEFT (-4250 2800);
DISPLAY 1.021277 (-4250 2800);
PAINT PURPLE (-4250 2800);
FORCENOTE
ALL OTHERS
(-4150 2550) 0;
DISPLAY LEFT (-4150 2550);
DISPLAY 1.021277 (-4150 2550);
PAINT PURPLE (-4150 2550);
FORCENOTE
FAB 1 PPO
(-3425 1350) 0;
DISPLAY LEFT (-3425 1350);
DISPLAY 1.021277 (-3425 1350);
PAINT PURPLE (-3425 1350);
FORCENOTE
0
(-4175 1350) 0;
DISPLAY LEFT (-4175 1350);
DISPLAY 1.021277 (-4175 1350);
PAINT PURPLE (-4175 1350);
FORCENOTE
0
(-4175 1225) 0;
DISPLAY LEFT (-4175 1225);
DISPLAY 1.021277 (-4175 1225);
PAINT PURPLE (-4175 1225);
FORCENOTE
0
(-4175 1100) 0;
DISPLAY LEFT (-4175 1100);
DISPLAY 1.021277 (-4175 1100);
PAINT PURPLE (-4175 1100);
FORCENOTE
FM_BOARD_ID[4:0]
(-4175 2925) 0;
DISPLAY LEFT (-4175 2925);
DISPLAY 1.021277 (-4175 2925);
PAINT PURPLE (-4175 2925);
FORCENOTE
FM_BOARD_REV_ID[2:0]
(-4350 1475) 0;
DISPLAY LEFT (-4350 1475);
DISPLAY 1.021277 (-4350 1475);
PAINT PURPLE (-4350 1475);
FORCENOTE
ALL OTHERS
(-4200 975) 0;
DISPLAY LEFT (-4200 975);
DISPLAY 1.021277 (-4200 975);
PAINT PURPLE (-4200 975);
FORCENOTE
0
(-3900 1100) 0;
DISPLAY LEFT (-3900 1100);
DISPLAY 1.021277 (-3900 1100);
PAINT PURPLE (-3900 1100);
FORCENOTE
0
(-3900 1350) 0;
DISPLAY LEFT (-3900 1350);
DISPLAY 1.021277 (-3900 1350);
PAINT PURPLE (-3900 1350);
FORCENOTE
1
(-3900 1225) 0;
DISPLAY LEFT (-3900 1225);
DISPLAY 1.021277 (-3900 1225);
PAINT PURPLE (-3900 1225);
FORCENOTE
VOLUME
(-3400 1100) 0;
DISPLAY LEFT (-3400 1100);
DISPLAY 1.021277 (-3400 1100);
PAINT PURPLE (-3400 1100);
FORCENOTE
REV
(-3350 1475) 0;
DISPLAY LEFT (-3350 1475);
DISPLAY 1.021277 (-3350 1475);
PAINT PURPLE (-3350 1475);
FORCENOTE
1
(-4050 1100) 0;
DISPLAY LEFT (-4050 1100);
DISPLAY 1.021277 (-4050 1100);
PAINT PURPLE (-4050 1100);
FORCENOTE
0
(-4050 1350) 0;
DISPLAY LEFT (-4050 1350);
DISPLAY 1.021277 (-4050 1350);
PAINT PURPLE (-4050 1350);
FORCENOTE
0
(-4050 1225) 0;
DISPLAY LEFT (-4050 1225);
DISPLAY 1.021277 (-4050 1225);
PAINT PURPLE (-4050 1225);
FORCENOTE
RESERVED
(-3450 975) 0;
DISPLAY LEFT (-3450 975);
DISPLAY 1.021277 (-3450 975);
PAINT PURPLE (-3450 975);
FORCENOTE
FAB 2 PO
(-3425 1225) 0;
DISPLAY LEFT (-3425 1225);
DISPLAY 1.021277 (-3425 1225);
PAINT PURPLE (-3425 1225);
FORCENOTE
REV
(-3425 2925) 0;
DISPLAY LEFT (-3425 2925);
DISPLAY 1.021277 (-3425 2925);
PAINT PURPLE (-3425 2925);
FORCENOTE
SINGLE SIDED
(-3425 2800) 0;
DISPLAY LEFT (-3425 2800);
DISPLAY 1.021277 (-3425 2800);
PAINT PURPLE (-3425 2800);
FORCENOTE
DOUBLE SIDED
(-3425 2675) 0;
DISPLAY LEFT (-3425 2675);
DISPLAY 1.021277 (-3425 2675);
PAINT PURPLE (-3425 2675);
FORCENOTE
TBD/RESERVED
(-3425 2550) 0;
DISPLAY LEFT (-3425 2550);
DISPLAY 1.021277 (-3425 2550);
PAINT PURPLE (-3425 2550);
QUIT
